# S9S_MB_2U (Grand Teton) — schematic netlist excerpt (pin names and nets, part order shuffled) for the footprints in the layout excerpt that follows; sources: Cadence DE-HDL packaged netlist, KiCad conversion of 03242023_DA0F0TMBIJ0_F0T_Motherboard_J_brd_V01_OCP.brd

PC1284  Q_CAP  100NF 50V 10% X7R  pkg C0402  page 300 : A = PVNN_MAIN_CPU1 ; B = GND
PC324  Q_CAPP  270UF 16V 20% OSCON  pkg THLF  page 267 : A = SW_P12V_PVCCIN_CPU0_FLT ; B = GND
R780  Q_RES  49.9 1% CHIP  pkg 0402LF  page 131 : A = FM_CPU_FBRK_DEBUG_N ; B = FM_CPU_FBRK_DEBUG_R_N

(kicad_pcb
	(version 20260206)
	(generator "pcbnew")
	(generator_version "10.0")
	(general
		(thickness 1.6)
		(legacy_teardrops no)
	)
	(paper "A4")
	(title_block
		(title "03242023_DA0F0TMBIJ0_F0T_Motherboard_J_brd_V01_OCP.brd")
		(comment 1 "Grand Teton / footprints 3882-3884 of 6105")
	)
	(layers
		(0 "F.Cu" signal "TOP")
		(4 "In1.Cu" signal "GND")
		(6 "In2.Cu" signal "IN1")
		(8 "In3.Cu" signal "GND1")
		(10 "In4.Cu" signal "IN2")
		(12 "In5.Cu" signal "GND2")
		(14 "In6.Cu" signal "IN3")
		(16 "In7.Cu" signal "GND3")
		(18 "In8.Cu" signal "VCC")
		(20 "In9.Cu" signal "VCC1")
		(22 "In10.Cu" signal "GND4")
		(24 "In11.Cu" signal "IN4")
		(26 "In12.Cu" signal "GND5")
		(28 "In13.Cu" signal "IN5")
		(30 "In14.Cu" signal "GND6")
		(32 "In15.Cu" signal "IN6")
		(34 "In16.Cu" signal "GND7")
		(2 "B.Cu" signal "BOTTOM")
		(9 "F.Adhes" user "F.Adhesive")
		(11 "B.Adhes" user "B.Adhesive")
		(13 "F.Paste" user "Package Geometry/Pastemask Top")
		(15 "B.Paste" user "Package Geometry/Pastemask Bottom")
		(5 "F.SilkS" user "Ref Des/Silkscreen Top")
		(7 "B.SilkS" user "Ref Des/Silkscreen Bottom")
		(1 "F.Mask" user "Board Geometry/Soldermask Top")
		(3 "B.Mask" user "Board Geometry/Soldermask Bottom")
		(17 "Dwgs.User" user "User.Drawings")
		(19 "Cmts.User" user "User.Comments")
		(21 "Eco1.User" user "User.Eco1")
		(23 "Eco2.User" user "User.Eco2")
		(25 "Edge.Cuts" user "Board Geometry/Outline")
		(27 "Margin" user)
		(31 "F.CrtYd" user "Package Geometry/Place Bound Top")
		(29 "B.CrtYd" user "Package Geometry/Place Bound Bottom")
		(35 "F.Fab" user "Ref Des/Assembly Top")
		(33 "B.Fab" user "Ref Des/Assembly Bottom")
	)
	(footprint ""
		(layer "F.Cu")
		(at 404.006812 -57.791604)
		(property "Reference" "R780"
			(at 0 0 0)
			(layer "F.SilkS")
			(hide yes)
			(effects
				(font
					(size 1.27 1.27)
				)
			)
		)
		(property "Value" ""
			(at 0 0 0)
			(layer "F.Fab")
			(effects
				(font
					(size 1.27 1.27)
				)
			)
		)
		(duplicate_pad_numbers_are_jumpers no)
		(fp_line
			(start -0.7874 -0.4064)
			(end 0.7874 -0.4064)
			(stroke
				(width 0.1524)
				(type default)
			)
			(layer "F.SilkS")
		)
		(fp_line
			(start -0.7874 0.4064)
			(end -0.7874 -0.4064)
			(stroke
				(width 0.1524)
				(type default)
			)
			(layer "F.SilkS")
		)
		(fp_line
			(start 0.7874 -0.4064)
			(end 0.7874 0.4064)
			(stroke
				(width 0.1524)
				(type default)
			)
			(layer "F.SilkS")
		)
		(fp_line
			(start 0.7874 0.4064)
			(end -0.7874 0.4064)
			(stroke
				(width 0.1524)
				(type default)
			)
			(layer "F.SilkS")
		)
		(fp_line
			(start -0.67945 -0.305054)
			(end -0.12065 -0.305054)
			(stroke
				(width 0.1)
				(type default)
			)
			(layer "F.Fab")
		)
		(fp_line
			(start -0.67945 0.3048)
			(end -0.67945 -0.305054)
			(stroke
				(width 0.1)
				(type default)
			)
			(layer "F.Fab")
		)
		(fp_line
			(start -0.12065 -0.305054)
			(end -0.12065 -0.2794)
			(stroke
				(width 0.1)
				(type default)
			)
			(layer "F.Fab")
		)
		(fp_line
			(start -0.12065 -0.2794)
			(end 0.12065 -0.2794)
			(stroke
				(width 0.1)
				(type default)
			)
			(layer "F.Fab")
		)
		(fp_line
			(start -0.12065 0.2794)
			(end -0.12065 0.3048)
			(stroke
				(width 0.1)
				(type default)
			)
			(layer "F.Fab")
		)
		(fp_line
			(start -0.12065 0.3048)
			(end -0.67945 0.3048)
			(stroke
				(width 0.1)
				(type default)
			)
			(layer "F.Fab")
		)
		(fp_line
			(start 0.120396 0.2794)
			(end -0.12065 0.2794)
			(stroke
				(width 0.1)
				(type default)
			)
			(layer "F.Fab")
		)
		(fp_line
			(start 0.120396 0.3048)
			(end 0.120396 0.2794)
			(stroke
				(width 0.1)
				(type default)
			)
			(layer "F.Fab")
		)
		(fp_line
			(start 0.12065 -0.3048)
			(end 0.67945 -0.3048)
			(stroke
				(width 0.1)
				(type default)
			)
			(layer "F.Fab")
		)
		(fp_line
			(start 0.12065 -0.2794)
			(end 0.12065 -0.3048)
			(stroke
				(width 0.1)
				(type default)
			)
			(layer "F.Fab")
		)
		(fp_line
			(start 0.67945 -0.3048)
			(end 0.67945 0.3048)
			(stroke
				(width 0.1)
				(type default)
			)
			(layer "F.Fab")
		)
		(fp_line
			(start 0.67945 0.3048)
			(end 0.120396 0.3048)
			(stroke
				(width 0.1)
				(type default)
			)
			(layer "F.Fab")
		)
		(pad "1" smd circle
			(at -0.40005 0)
			(size 0 0)
			(layers "F.Cu" "F.Mask" "F.Paste")
			(net "FM_CPU_FBRK_DEBUG_N")
		)
		(pad "2" smd circle
			(at 0.40005 0)
			(size 0 0)
			(layers "F.Cu" "F.Mask" "F.Paste")
			(net "FM_CPU_FBRK_DEBUG_R_N")
		)
	)
	(footprint ""
		(layer "F.Cu")
		(at 352.839274 -343.902284 90)
		(property "Reference" "PC324"
			(at 0 0 90)
			(layer "F.SilkS")
			(hide yes)
			(effects
				(font
					(size 1.27 1.27)
				)
			)
		)
		(property "Value" ""
			(at 0 0 90)
			(layer "F.Fab")
			(effects
				(font
					(size 1.27 1.27)
				)
			)
		)
		(duplicate_pad_numbers_are_jumpers no)
		(fp_line
			(start -3.400044 1.249934)
			(end 3.400044 1.249934)
			(stroke
				(width 0.1524)
				(type default)
			)
			(layer "F.SilkS")
		)
		(fp_circle
			(center 0 1.249934)
			(end 0 4.649978)
			(stroke
				(width 0.1524)
				(type default)
			)
			(fill no)
			(layer "F.SilkS")
		)
		(fp_poly
			(pts
				(arc
					(start -3.400044 1.249934)
					(mid 0 4.649978)
					(end 3.400044 1.249934)
				)
			)
			(stroke
				(width 0)
				(type default)
			)
			(fill yes)
			(layer "F.SilkS")
		)
		(fp_circle
			(center 0 1.249934)
			(end 0 4.649978)
			(stroke
				(width 0.1)
				(type default)
			)
			(fill no)
			(layer "F.Fab")
		)
		(pad "1" thru_hole rect
			(at 0 0 90)
			(size 1.524 1.524)
			(drill 1.016)
			(layers "*.Cu" "*.Mask")
			(remove_unused_layers no)
			(net "SW_P12V_PVCCIN_CPU0_FLT")
			(clearance 0)
			(padstack
				(mode front_inner_back)
				(layer "Inner"
					(shape circle)
					(size 1.524 1.524)
					(clearance 0)
				)
				(layer "B.Cu"
					(shape rect)
					(size 1.524 1.524)
					(clearance 0)
				)
			)
		)
		(pad "2" thru_hole circle
			(at 0 2.500122 90)
			(size 1.524 1.524)
			(drill 1.016)
			(layers "*.Cu" "*.Mask")
			(remove_unused_layers no)
			(net "GND")
			(clearance 0)
		)
	)
	(footprint ""
		(layer "F.Cu")
		(at 36.84143 -174.804578)
		(property "Reference" "PC1284"
			(at 0 0 0)
			(layer "F.SilkS")
			(hide yes)
			(effects
				(font
					(size 1.27 1.27)
				)
			)
		)
		(property "Value" ""
			(at 0 0 0)
			(layer "F.Fab")
			(effects
				(font
					(size 1.27 1.27)
				)
			)
		)
		(duplicate_pad_numbers_are_jumpers no)
		(fp_line
			(start -0.7874 -0.4064)
			(end 0.7874 -0.4064)
			(stroke
				(width 0.1524)
				(type default)
			)
			(layer "F.SilkS")
		)
		(fp_line
			(start -0.7874 0.4064)
			(end -0.7874 -0.4064)
			(stroke
				(width 0.1524)
				(type default)
			)
			(layer "F.SilkS")
		)
		(fp_line
			(start 0.7874 -0.4064)
			(end 0.7874 0.4064)
			(stroke
				(width 0.1524)
				(type default)
			)
			(layer "F.SilkS")
		)
		(fp_line
			(start 0.7874 0.4064)
			(end -0.7874 0.4064)
			(stroke
				(width 0.1524)
				(type default)
			)
			(layer "F.SilkS")
		)
		(fp_line
			(start -0.67945 -0.305054)
			(end -0.12065 -0.305054)
			(stroke
				(width 0.1)
				(type default)
			)
			(layer "F.Fab")
		)
		(fp_line
			(start -0.67945 0.3048)
			(end -0.67945 -0.305054)
			(stroke
				(width 0.1)
				(type default)
			)
			(layer "F.Fab")
		)
		(fp_line
			(start -0.12065 -0.305054)
			(end -0.12065 -0.2794)
			(stroke
				(width 0.1)
				(type default)
			)
			(layer "F.Fab")
		)
		(fp_line
			(start -0.12065 -0.2794)
			(end 0.12065 -0.2794)
			(stroke
				(width 0.1)
				(type default)
			)
			(layer "F.Fab")
		)
		(fp_line
			(start -0.12065 0.2794)
			(end -0.12065 0.3048)
			(stroke
				(width 0.1)
				(type default)
			)
			(layer "F.Fab")
		)
		(fp_line
			(start -0.12065 0.3048)
			(end -0.67945 0.3048)
			(stroke
				(width 0.1)
				(type default)
			)
			(layer "F.Fab")
		)
		(fp_line
			(start 0.120396 0.2794)
			(end -0.12065 0.2794)
			(stroke
				(width 0.1)
				(type default)
			)
			(layer "F.Fab")
		)
		(fp_line
			(start 0.120396 0.3048)
			(end 0.120396 0.2794)
			(stroke
				(width 0.1)
				(type default)
			)
			(layer "F.Fab")
		)
		(fp_line
			(start 0.12065 -0.3048)
			(end 0.67945 -0.3048)
			(stroke
				(width 0.1)
				(type default)
			)
			(layer "F.Fab")
		)
		(fp_line
			(start 0.12065 -0.2794)
			(end 0.12065 -0.3048)
			(stroke
				(width 0.1)
				(type default)
			)
			(layer "F.Fab")
		)
		(fp_line
			(start 0.67945 -0.3048)
			(end 0.67945 0.3048)
			(stroke
				(width 0.1)
				(type default)
			)
			(layer "F.Fab")
		)
		(fp_line
			(start 0.67945 0.3048)
			(end 0.120396 0.3048)
			(stroke
				(width 0.1)
				(type default)
			)
			(layer "F.Fab")
		)
		(pad "1" smd circle
			(at -0.40005 0)
			(size 0 0)
			(layers "F.Cu" "F.Mask" "F.Paste")
			(net "PVNN_MAIN_CPU1")
		)
		(pad "2" smd circle
			(at 0.40005 0)
			(size 0 0)
			(layers "F.Cu" "F.Mask" "F.Paste")
			(net "GND")
		)
	)
)
